# TIMECARD (Time Appliance Project (Time Card)) — schematic netlist excerpt (pin names and nets, part order shuffled) for the footprints in the layout excerpt that follows; sources: Cadence DE-HDL packaged netlist, KiCad conversion of R4006-B0001-02_R01.brd

TP202  TP_PIONT  pkg TP010CT020B030_PTH  page 25 : \1\ = IO_L22N_35
C305  CAPACITOR  0.1UF 25V 10%  pkg SMC_0402R_H022  page 17 : \1\ = SG ; \2\ = XP3R3V_FPGA

(kicad_pcb
	(version 20260206)
	(generator "pcbnew")
	(generator_version "10.0")
	(general
		(thickness 1.6)
		(legacy_teardrops no)
	)
	(paper "A4")
	(title_block
		(title "timecard-production-celestica-r4006 — R4006-B0001-02_R01.brd")
		(comment 1 "Time Appliance Project (Time Card) / footprints 291-292 of 1113")
	)
	(layers
		(0 "F.Cu" signal "TOP")
		(4 "In1.Cu" signal "L02_GND1")
		(6 "In2.Cu" signal "L03_SIG1")
		(8 "In3.Cu" signal "L04_GND2")
		(10 "In4.Cu" signal "L05_VCC1")
		(12 "In5.Cu" signal "L06_VCC2")
		(14 "In6.Cu" signal "L07_GND3")
		(16 "In7.Cu" signal "L08_SIG2")
		(18 "In8.Cu" signal "L09_GND4")
		(2 "B.Cu" signal "BOTTOM")
		(9 "F.Adhes" user "F.Adhesive")
		(11 "B.Adhes" user "B.Adhesive")
		(13 "F.Paste" user "Package Geometry/Pastemask Top")
		(15 "B.Paste" user "Package Geometry/Pastemask Bottom")
		(5 "F.SilkS" user "Ref Des/Silkscreen Top")
		(7 "B.SilkS" user "Ref Des/Silkscreen Bottom")
		(1 "F.Mask" user "Board Geometry/Soldermask Top")
		(3 "B.Mask" user "Board Geometry/Soldermask Bottom")
		(17 "Dwgs.User" user "User.Drawings")
		(19 "Cmts.User" user "User.Comments")
		(21 "Eco1.User" user "User.Eco1")
		(23 "Eco2.User" user "User.Eco2")
		(25 "Edge.Cuts" user "Board Geometry/Outline")
		(27 "Margin" user)
		(31 "F.CrtYd" user "Package Geometry/Place Bound Top")
		(29 "B.CrtYd" user "Package Geometry/Place Bound Bottom")
		(35 "F.Fab" user "Ref Des/Assembly Top")
		(33 "B.Fab" user "Ref Des/Assembly Bottom")
	)
	(footprint ""
		(layer "F.Cu")
		(at 162.56 -28.829 180)
		(property "Reference" "C305"
			(at -2.667 0.72263 0)
			(unlocked yes)
			(layer "F.SilkS")
			(effects
				(font
					(size 0.7874 0.5842)
					(thickness 0.1524)
				)
			)
		)
		(property "Value" "VAL*"
			(at 0.0762 2.067306 180)
			(unlocked yes)
			(layer "F.Fab")
			(hide yes)
			(effects
				(font
					(size 0.7874 0.5842)
					(thickness 0.1524)
				)
			)
		)
		(property "Tolerance" "TOL*"
			(at 0.0762 3.032506 180)
			(unlocked yes)
			(layer "Cmts.User")
			(hide yes)
			(effects
				(font
					(size 0.7874 0.5842)
					(thickness 0.1524)
				)
			)
		)
		(property "User Part Number" "PARTNUM*"
			(at 0.1016 4.023106 180)
			(unlocked yes)
			(layer "Cmts.User")
			(hide yes)
			(effects
				(font
					(size 0.7874 0.5842)
					(thickness 0.1524)
				)
			)
		)
		(property "Device Type" "CAPACITOR-G105-0B104-EK,0.1UF,A"
			(at 0.0508 1.127506 180)
			(unlocked yes)
			(layer "F.Fab")
			(hide yes)
			(effects
				(font
					(size 0.7874 0.5842)
					(thickness 0.1524)
				)
			)
		)
		(duplicate_pad_numbers_are_jumpers no)
		(fp_line
			(start 1.143 0.5588)
			(end 1.143 -0.5588)
			(stroke
				(width 0.1)
				(type default)
			)
			(layer "F.SilkS")
		)
		(fp_line
			(start 1.143 -0.5588)
			(end -1.143 -0.5588)
			(stroke
				(width 0.1)
				(type default)
			)
			(layer "F.SilkS")
		)
		(fp_line
			(start -1.143 0.5588)
			(end 1.143 0.5588)
			(stroke
				(width 0.1)
				(type default)
			)
			(layer "F.SilkS")
		)
		(fp_line
			(start -1.143 -0.5588)
			(end -1.143 0.5588)
			(stroke
				(width 0.1)
				(type default)
			)
			(layer "F.SilkS")
		)
		(fp_rect
			(start 1.143 -0.5588)
			(end -1.143 0.5588)
			(stroke
				(width 0)
				(type default)
			)
			(fill no)
			(layer "F.CrtYd")
		)
		(fp_line
			(start 0.508 0.3048)
			(end 0.508 -0.3048)
			(stroke
				(width 0.1)
				(type default)
			)
			(layer "F.Fab")
		)
		(fp_line
			(start 0.508 -0.3048)
			(end -0.508 -0.3048)
			(stroke
				(width 0.1)
				(type default)
			)
			(layer "F.Fab")
		)
		(fp_line
			(start -0.508 0.3048)
			(end 0.508 0.3048)
			(stroke
				(width 0.1)
				(type default)
			)
			(layer "F.Fab")
		)
		(fp_line
			(start -0.508 -0.3048)
			(end -0.508 0.3048)
			(stroke
				(width 0.1)
				(type default)
			)
			(layer "F.Fab")
		)
		(pad "1" smd rect
			(at -0.5334 0 180)
			(size 0.7112 0.6096)
			(layers "F.Cu" "F.Mask" "F.Paste")
			(net "SG")
		)
		(pad "2" smd rect
			(at 0.5334 0 180)
			(size 0.7112 0.6096)
			(layers "F.Cu" "F.Mask" "F.Paste")
			(net "XP3R3V_FPGA")
		)
		(zone
			(layer "F.Cu")
			(hatch none 0.5)
			(connect_pads
				(clearance 0)
			)
			(min_thickness 0.25)
			(keepout
				(tracks allowed)
				(vias not_allowed)
				(pads allowed)
				(copperpour not_allowed)
				(footprints allowed)
			)
			(placement
				(enabled no)
				(sheetname "")
			)
			(fill
				(thermal_gap 0.5)
				(thermal_bridge_width 0.5)
				(island_removal_mode 0)
			)
			(polygon
				(pts
					(xy 162.4838 -28.5242) (xy 162.6362 -28.5242) (xy 162.6362 -29.1338) (xy 162.4838 -29.1338)
				)
			)
		)
		(zone
			(layer "F.Cu")
			(hatch none 0.5)
			(connect_pads
				(clearance 0)
			)
			(min_thickness 0.25)
			(keepout
				(tracks not_allowed)
				(vias allowed)
				(pads allowed)
				(copperpour not_allowed)
				(footprints allowed)
			)
			(placement
				(enabled no)
				(sheetname "")
			)
			(fill
				(thermal_gap 0.5)
				(thermal_bridge_width 0.5)
				(island_removal_mode 0)
			)
			(polygon
				(pts
					(xy 162.4838 -28.5242) (xy 162.6362 -28.5242) (xy 162.6362 -29.1338) (xy 162.4838 -29.1338)
				)
			)
		)
	)
	(footprint ""
		(layer "F.Cu")
		(at 118.491 -28.0416 90)
		(property "Reference" "TP202"
			(at -2.8194 1.30175 90)
			(unlocked yes)
			(layer "F.SilkS")
			(effects
				(font
					(size 0.635 0.4064)
					(thickness 0.1524)
				)
				(justify left)
			)
		)
		(property "Value" ""
			(at 0 0 90)
			(layer "F.Fab")
			(effects
				(font
					(size 1.27 1.27)
				)
			)
		)
		(property "Device Type" "TP_PIONT-TP010CT020B030_PTH-TPA"
			(at -1.341882 0.996696 90)
			(unlocked yes)
			(layer "F.Fab")
			(hide yes)
			(effects
				(font
					(size 0.7874 0.5842)
					(thickness 0.1524)
				)
				(justify left)
			)
		)
		(duplicate_pad_numbers_are_jumpers no)
		(fp_poly
			(pts
				(arc
					(start 0 0.889)
					(mid 0 -0.889)
					(end 0 0.889)
				)
			)
			(stroke
				(width 0)
				(type default)
			)
			(fill no)
			(layer "B.CrtYd")
		)
		(fp_poly
			(pts
				(arc
					(start 0 0.889)
					(mid 0 -0.889)
					(end 0 0.889)
				)
			)
			(stroke
				(width 0)
				(type default)
			)
			(fill no)
			(layer "F.CrtYd")
		)
		(pad "1" thru_hole circle
			(at 0 0 90)
			(size 0.508 0.508)
			(drill 0.254)
			(layers "*.Cu" "*.Mask")
			(remove_unused_layers no)
			(net "IO_L22N_35")
			(clearance 0.1016)
			(padstack
				(mode front_inner_back)
				(layer "Inner"
					(shape circle)
					(size 0.508 0.508)
					(clearance 0.1016)
				)
				(layer "B.Cu"
					(shape circle)
					(size 0.762 0.762)
					(clearance -0.0254)
				)
			)
		)
	)
)
